#ISCELL
  logical_power cad_note *
  *
#ISCELL
  mstr_misc dns *
  *
#ISCELL
  pure_quanta quanta_title_block_c *
  *
#ISCELL
  standard offpage *
  page236_i31
#ISCELL
  logical_power universal_gnd *
  page236_i41
#CELL
  pure_quanta q_cap *
  page236_i42
#CELL
  pure_quanta q_res *
  page236_i43
#ISCELL
  logical_power universal_gnd *
  page236_i44
#CELL
  pure_quanta q_res *
  page236_i45
#CELL
  pure_quanta q_res *
  page236_i46
#ISCELL
  logical_power universal_gnd *
  page236_i47
#ISCELL
  logical_power universal_gnd *
  page236_i48
#CELL
  pure_quanta q_cap *
  page236_i49
#CELL
  pure_quanta mp5016gqhlz *
  page236_i50
#ISCELL
  logical_power universal_gnd *
  page236_i51
#CELL
  pure_quanta q_cap *
  page236_i52
#ISCELL
  logical_power universal_gnd *
  page236_i53
#CELL
  pure_quanta q_cap *
  page236_i54
#CELL
  pure_quanta q_cap *
  page236_i55
#ISCELL
  logical_power universal_power *
  page236_i56
#ISCELL
  logical_power universal_power *
  page236_i57
#ISCELL
  standard offpage *
  page236_i58
#ISCELL
  logical_power gnd *
  page236_i59
#CELL
  pure_quanta q_cap *
  page236_i60
#ISCELL
  logical_power gnd *
  page236_i61
#CELL
  pure_quanta q_res *
  page236_i62
#CELL
  pure_quanta q_cap *
  page236_i63
#ISCELL
  logical_power gnd *
  page236_i64
#CELL
  pure_quanta q_res *
  page236_i65
#ISCELL
  logical_power gnd *
  page236_i66
#ISCELL
  logical_power gnd *
  page236_i67
#CELL
  pure_quanta q_cap *
  page236_i68
#ISCELL
  logical_power gnd *
  page236_i69
#CELL
  pure_quanta rs31312r *
  page236_i70
#ISCELL
  logical_power universal_power *
  page236_i71
#CELL
  pure_quanta q_res *
  page236_i72
#ISCELL
  logical_power gnd *
  page236_i73
#CELL
  pure_quanta q_cap *
  page236_i74
#CELL
  pure_quanta q_res *
  page236_i75
#CELL
  pure_quanta q_res *
  page236_i76
#CELL
  pure_quanta q_res *
  page236_i77
#ISCELL
  standard offpage *
  page236_i78
#ISCELL
  standard offpage *
  page236_i79
#ISCELL
  logical_power vccaux15 *
  page236_i80
#CELL
  pure_quanta q_res *
  page236_i81
#CELL
  pure_quanta q_res *
  page236_i82
#CELL
  pure_quanta q_res *
  page236_i83
#ISCELL
  logical_power gnd *
  page236_i84
#CELL
  pure_quanta q_res *
  page236_i85
#CELL
  pure_quanta q_res *
  page236_i86
#ISCELL
  logical_power vccaux15 *
  page236_i87
#CELL
  pure_quanta q_cap *
  page236_i88
#CELL
  pure_quanta q_res *
  page236_i89
#ISCELL
  logical_power universal_power *
  page236_i90
#CELL
  pure_quanta q_cap *
  page236_i91
#ISCELL
  logical_power gnd *
  page236_i92
#ISCELL
  standard offpage *
  page236_i93
#ISCELL
  logical_power universal_power *
  page236_i94
#ISCELL
  standard offpage *
  page236_i95
#ISCELL
  standard offpage *
  page236_i96
